(kicad_pcb
	(version 20260206)
	(generator "pcbnew")
	(generator_version "10.0")
	(general
		(thickness 1.6)
		(legacy_teardrops no)
	)
	(paper "A4")
	(title_block
		(title "04192023_DAF0TMB3IC0_F0TG_MB_C_brd_V02_OCP.brd")
		(comment 1 "Grand Teton / footprints 3559-3566 of 8354")
	)
	(layers
		(0 "F.Cu" signal "TOP")
		(4 "In1.Cu" signal "GND")
		(6 "In2.Cu" signal "IN1")
		(8 "In3.Cu" signal "GND1")
		(10 "In4.Cu" signal "IN2")
		(12 "In5.Cu" signal "GND2")
		(14 "In6.Cu" signal "IN3")
		(16 "In7.Cu" signal "GND3")
		(18 "In8.Cu" signal "VCC")
		(20 "In9.Cu" signal "VCC1")
		(22 "In10.Cu" signal "GND4")
		(24 "In11.Cu" signal "IN4")
		(26 "In12.Cu" signal "GND5")
		(28 "In13.Cu" signal "IN5")
		(30 "In14.Cu" signal "GND6")
		(32 "In15.Cu" signal "IN6")
		(34 "In16.Cu" signal "GND7")
		(2 "B.Cu" signal "BOTTOM")
		(9 "F.Adhes" user "F.Adhesive")
		(11 "B.Adhes" user "B.Adhesive")
		(13 "F.Paste" user "Package Geometry/Pastemask Top")
		(15 "B.Paste" user "Package Geometry/Pastemask Bottom")
		(5 "F.SilkS" user "Ref Des/Silkscreen Top")
		(7 "B.SilkS" user "Ref Des/Silkscreen Bottom")
		(1 "F.Mask" user "Board Geometry/Soldermask Top")
		(3 "B.Mask" user "Board Geometry/Soldermask Bottom")
		(17 "Dwgs.User" user "User.Drawings")
		(19 "Cmts.User" user "User.Comments")
		(21 "Eco1.User" user "User.Eco1")
		(23 "Eco2.User" user "User.Eco2")
		(25 "Edge.Cuts" user "Board Geometry/Outline")
		(27 "Margin" user)
		(31 "F.CrtYd" user "Package Geometry/Place Bound Top")
		(29 "B.CrtYd" user "Package Geometry/Place Bound Bottom")
		(35 "F.Fab" user "Ref Des/Assembly Top")
		(33 "B.Fab" user "Ref Des/Assembly Bottom")
	)
	(footprint ""
		(layer "F.Cu")
		(at 435.997858 -106.76636 180)
		(property "Reference" "PR3798"
			(at 0 0 180)
			(layer "F.SilkS")
			(hide yes)
			(effects
				(font
					(size 1.27 1.27)
				)
			)
		)
		(property "Value" ""
			(at 0 0 180)
			(layer "F.Fab")
			(effects
				(font
					(size 1.27 1.27)
				)
			)
		)
		(duplicate_pad_numbers_are_jumpers no)
		(fp_line
			(start 0.7874 0.4064)
			(end -0.7874 0.4064)
			(stroke
				(width 0.1524)
				(type default)
			)
			(layer "F.SilkS")
		)
		(fp_line
			(start 0.7874 -0.4064)
			(end 0.7874 0.4064)
			(stroke
				(width 0.1524)
				(type default)
			)
			(layer "F.SilkS")
		)
		(fp_line
			(start -0.7874 0.4064)
			(end -0.7874 -0.4064)
			(stroke
				(width 0.1524)
				(type default)
			)
			(layer "F.SilkS")
		)
		(fp_line
			(start -0.7874 -0.4064)
			(end 0.7874 -0.4064)
			(stroke
				(width 0.1524)
				(type default)
			)
			(layer "F.SilkS")
		)
		(fp_line
			(start 0.67945 0.3048)
			(end 0.120396 0.3048)
			(stroke
				(width 0.1)
				(type default)
			)
			(layer "F.Fab")
		)
		(fp_line
			(start 0.67945 -0.3048)
			(end 0.67945 0.3048)
			(stroke
				(width 0.1)
				(type default)
			)
			(layer "F.Fab")
		)
		(fp_line
			(start 0.12065 -0.2794)
			(end 0.12065 -0.3048)
			(stroke
				(width 0.1)
				(type default)
			)
			(layer "F.Fab")
		)
		(fp_line
			(start 0.12065 -0.3048)
			(end 0.67945 -0.3048)
			(stroke
				(width 0.1)
				(type default)
			)
			(layer "F.Fab")
		)
		(fp_line
			(start 0.120396 0.3048)
			(end 0.120396 0.2794)
			(stroke
				(width 0.1)
				(type default)
			)
			(layer "F.Fab")
		)
		(fp_line
			(start 0.120396 0.2794)
			(end -0.12065 0.2794)
			(stroke
				(width 0.1)
				(type default)
			)
			(layer "F.Fab")
		)
		(fp_line
			(start -0.12065 0.3048)
			(end -0.67945 0.3048)
			(stroke
				(width 0.1)
				(type default)
			)
			(layer "F.Fab")
		)
		(fp_line
			(start -0.12065 0.2794)
			(end -0.12065 0.3048)
			(stroke
				(width 0.1)
				(type default)
			)
			(layer "F.Fab")
		)
		(fp_line
			(start -0.12065 -0.2794)
			(end 0.12065 -0.2794)
			(stroke
				(width 0.1)
				(type default)
			)
			(layer "F.Fab")
		)
		(fp_line
			(start -0.12065 -0.305054)
			(end -0.12065 -0.2794)
			(stroke
				(width 0.1)
				(type default)
			)
			(layer "F.Fab")
		)
		(fp_line
			(start -0.67945 0.3048)
			(end -0.67945 -0.305054)
			(stroke
				(width 0.1)
				(type default)
			)
			(layer "F.Fab")
		)
		(fp_line
			(start -0.67945 -0.305054)
			(end -0.12065 -0.305054)
			(stroke
				(width 0.1)
				(type default)
			)
			(layer "F.Fab")
		)
		(pad "1" smd circle
			(at -0.40005 0 180)
			(size 0 0)
			(layers "F.Cu" "F.Mask" "F.Paste")
			(net "P3V3_AUX")
		)
		(pad "2" smd circle
			(at 0.40005 0 180)
			(size 0 0)
			(layers "F.Cu" "F.Mask" "F.Paste")
			(net "P3V3_OCP_VCC_1")
		)
	)
	(footprint ""
		(layer "F.Cu")
		(at 341.56904 -171.308522)
		(property "Reference" "PR295"
			(at 0 0 0)
			(layer "F.SilkS")
			(hide yes)
			(effects
				(font
					(size 1.27 1.27)
				)
			)
		)
		(property "Value" ""
			(at 0 0 0)
			(layer "F.Fab")
			(effects
				(font
					(size 1.27 1.27)
				)
			)
		)
		(duplicate_pad_numbers_are_jumpers no)
		(fp_line
			(start -0.7874 -0.4064)
			(end 0.7874 -0.4064)
			(stroke
				(width 0.1524)
				(type default)
			)
			(layer "F.SilkS")
		)
		(fp_line
			(start -0.7874 0.4064)
			(end -0.7874 -0.4064)
			(stroke
				(width 0.1524)
				(type default)
			)
			(layer "F.SilkS")
		)
		(fp_line
			(start 0.7874 -0.4064)
			(end 0.7874 0.4064)
			(stroke
				(width 0.1524)
				(type default)
			)
			(layer "F.SilkS")
		)
		(fp_line
			(start 0.7874 0.4064)
			(end -0.7874 0.4064)
			(stroke
				(width 0.1524)
				(type default)
			)
			(layer "F.SilkS")
		)
		(fp_line
			(start -0.67945 -0.305054)
			(end -0.12065 -0.305054)
			(stroke
				(width 0.1)
				(type default)
			)
			(layer "F.Fab")
		)
		(fp_line
			(start -0.67945 0.3048)
			(end -0.67945 -0.305054)
			(stroke
				(width 0.1)
				(type default)
			)
			(layer "F.Fab")
		)
		(fp_line
			(start -0.12065 -0.305054)
			(end -0.12065 -0.2794)
			(stroke
				(width 0.1)
				(type default)
			)
			(layer "F.Fab")
		)
		(fp_line
			(start -0.12065 -0.2794)
			(end 0.12065 -0.2794)
			(stroke
				(width 0.1)
				(type default)
			)
			(layer "F.Fab")
		)
		(fp_line
			(start -0.12065 0.2794)
			(end -0.12065 0.3048)
			(stroke
				(width 0.1)
				(type default)
			)
			(layer "F.Fab")
		)
		(fp_line
			(start -0.12065 0.3048)
			(end -0.67945 0.3048)
			(stroke
				(width 0.1)
				(type default)
			)
			(layer "F.Fab")
		)
		(fp_line
			(start 0.120396 0.2794)
			(end -0.12065 0.2794)
			(stroke
				(width 0.1)
				(type default)
			)
			(layer "F.Fab")
		)
		(fp_line
			(start 0.120396 0.3048)
			(end 0.120396 0.2794)
			(stroke
				(width 0.1)
				(type default)
			)
			(layer "F.Fab")
		)
		(fp_line
			(start 0.12065 -0.3048)
			(end 0.67945 -0.3048)
			(stroke
				(width 0.1)
				(type default)
			)
			(layer "F.Fab")
		)
		(fp_line
			(start 0.12065 -0.2794)
			(end 0.12065 -0.3048)
			(stroke
				(width 0.1)
				(type default)
			)
			(layer "F.Fab")
		)
		(fp_line
			(start 0.67945 -0.3048)
			(end 0.67945 0.3048)
			(stroke
				(width 0.1)
				(type default)
			)
			(layer "F.Fab")
		)
		(fp_line
			(start 0.67945 0.3048)
			(end 0.120396 0.3048)
			(stroke
				(width 0.1)
				(type default)
			)
			(layer "F.Fab")
		)
		(pad "1" smd circle
			(at -0.40005 0)
			(size 0 0)
			(layers "F.Cu" "F.Mask" "F.Paste")
			(net "VSENSE_VSS_SENSE_A_P0")
		)
		(pad "2" smd circle
			(at 0.40005 0)
			(size 0 0)
			(layers "F.Cu" "F.Mask" "F.Paste")
			(net "GND")
		)
	)
	(footprint ""
		(layer "F.Cu")
		(at 212.118956 -30.276292 -90)
		(property "Reference" "R3561"
			(at 0 0 270)
			(layer "F.SilkS")
			(hide yes)
			(effects
				(font
					(size 1.27 1.27)
				)
			)
		)
		(property "Value" ""
			(at 0 0 270)
			(layer "F.Fab")
			(effects
				(font
					(size 1.27 1.27)
				)
			)
		)
		(duplicate_pad_numbers_are_jumpers no)
		(fp_line
			(start -0.7874 0.4064)
			(end -0.7874 -0.4064)
			(stroke
				(width 0.1524)
				(type default)
			)
			(layer "F.SilkS")
		)
		(fp_line
			(start 0.7874 0.4064)
			(end -0.7874 0.4064)
			(stroke
				(width 0.1524)
				(type default)
			)
			(layer "F.SilkS")
		)
		(fp_line
			(start -0.7874 -0.4064)
			(end 0.7874 -0.4064)
			(stroke
				(width 0.1524)
				(type default)
			)
			(layer "F.SilkS")
		)
		(fp_line
			(start 0.7874 -0.4064)
			(end 0.7874 0.4064)
			(stroke
				(width 0.1524)
				(type default)
			)
			(layer "F.SilkS")
		)
		(fp_line
			(start -0.67945 0.3048)
			(end -0.67945 -0.305054)
			(stroke
				(width 0.1)
				(type default)
			)
			(layer "F.Fab")
		)
		(fp_line
			(start -0.12065 0.3048)
			(end -0.67945 0.3048)
			(stroke
				(width 0.1)
				(type default)
			)
			(layer "F.Fab")
		)
		(fp_line
			(start 0.120396 0.3048)
			(end 0.120396 0.2794)
			(stroke
				(width 0.1)
				(type default)
			)
			(layer "F.Fab")
		)
		(fp_line
			(start 0.67945 0.3048)
			(end 0.120396 0.3048)
			(stroke
				(width 0.1)
				(type default)
			)
			(layer "F.Fab")
		)
		(fp_line
			(start -0.12065 0.2794)
			(end -0.12065 0.3048)
			(stroke
				(width 0.1)
				(type default)
			)
			(layer "F.Fab")
		)
		(fp_line
			(start 0.120396 0.2794)
			(end -0.12065 0.2794)
			(stroke
				(width 0.1)
				(type default)
			)
			(layer "F.Fab")
		)
		(fp_line
			(start -0.12065 -0.2794)
			(end 0.12065 -0.2794)
			(stroke
				(width 0.1)
				(type default)
			)
			(layer "F.Fab")
		)
		(fp_line
			(start 0.12065 -0.2794)
			(end 0.12065 -0.3048)
			(stroke
				(width 0.1)
				(type default)
			)
			(layer "F.Fab")
		)
		(fp_line
			(start 0.12065 -0.3048)
			(end 0.67945 -0.3048)
			(stroke
				(width 0.1)
				(type default)
			)
			(layer "F.Fab")
		)
		(fp_line
			(start 0.67945 -0.3048)
			(end 0.67945 0.3048)
			(stroke
				(width 0.1)
				(type default)
			)
			(layer "F.Fab")
		)
		(fp_line
			(start -0.67945 -0.305054)
			(end -0.12065 -0.305054)
			(stroke
				(width 0.1)
				(type default)
			)
			(layer "F.Fab")
		)
		(fp_line
			(start -0.12065 -0.305054)
			(end -0.12065 -0.2794)
			(stroke
				(width 0.1)
				(type default)
			)
			(layer "F.Fab")
		)
		(pad "1" smd circle
			(at -0.40005 0 270)
			(size 0 0)
			(layers "F.Cu" "F.Mask" "F.Paste")
			(net "P12V_SCM_ADC_ALERT_R")
		)
		(pad "2" smd circle
			(at 0.40005 0 270)
			(size 0 0)
			(layers "F.Cu" "F.Mask" "F.Paste")
			(net "P12V_SCM_ADC_ALERT")
		)
	)
	(footprint ""
		(layer "F.Cu")
		(at 179.939442 -26.240232)
		(property "Reference" "PC2241"
			(at 0 0 0)
			(layer "F.SilkS")
			(hide yes)
			(effects
				(font
					(size 1.27 1.27)
				)
			)
		)
		(property "Value" ""
			(at 0 0 0)
			(layer "F.Fab")
			(effects
				(font
					(size 1.27 1.27)
				)
			)
		)
		(duplicate_pad_numbers_are_jumpers no)
		(fp_line
			(start -0.7874 -0.4064)
			(end 0.7874 -0.4064)
			(stroke
				(width 0.1524)
				(type default)
			)
			(layer "F.SilkS")
		)
		(fp_line
			(start -0.7874 0.4064)
			(end -0.7874 -0.4064)
			(stroke
				(width 0.1524)
				(type default)
			)
			(layer "F.SilkS")
		)
		(fp_line
			(start 0.7874 -0.4064)
			(end 0.7874 0.4064)
			(stroke
				(width 0.1524)
				(type default)
			)
			(layer "F.SilkS")
		)
		(fp_line
			(start 0.7874 0.4064)
			(end -0.7874 0.4064)
			(stroke
				(width 0.1524)
				(type default)
			)
			(layer "F.SilkS")
		)
		(fp_line
			(start -0.67945 -0.305054)
			(end -0.12065 -0.305054)
			(stroke
				(width 0.1)
				(type default)
			)
			(layer "F.Fab")
		)
		(fp_line
			(start -0.67945 0.3048)
			(end -0.67945 -0.305054)
			(stroke
				(width 0.1)
				(type default)
			)
			(layer "F.Fab")
		)
		(fp_line
			(start -0.12065 -0.305054)
			(end -0.12065 -0.2794)
			(stroke
				(width 0.1)
				(type default)
			)
			(layer "F.Fab")
		)
		(fp_line
			(start -0.12065 -0.2794)
			(end 0.12065 -0.2794)
			(stroke
				(width 0.1)
				(type default)
			)
			(layer "F.Fab")
		)
		(fp_line
			(start -0.12065 0.2794)
			(end -0.12065 0.3048)
			(stroke
				(width 0.1)
				(type default)
			)
			(layer "F.Fab")
		)
		(fp_line
			(start -0.12065 0.3048)
			(end -0.67945 0.3048)
			(stroke
				(width 0.1)
				(type default)
			)
			(layer "F.Fab")
		)
		(fp_line
			(start 0.120396 0.2794)
			(end -0.12065 0.2794)
			(stroke
				(width 0.1)
				(type default)
			)
			(layer "F.Fab")
		)
		(fp_line
			(start 0.120396 0.3048)
			(end 0.120396 0.2794)
			(stroke
				(width 0.1)
				(type default)
			)
			(layer "F.Fab")
		)
		(fp_line
			(start 0.12065 -0.3048)
			(end 0.67945 -0.3048)
			(stroke
				(width 0.1)
				(type default)
			)
			(layer "F.Fab")
		)
		(fp_line
			(start 0.12065 -0.2794)
			(end 0.12065 -0.3048)
			(stroke
				(width 0.1)
				(type default)
			)
			(layer "F.Fab")
		)
		(fp_line
			(start 0.67945 -0.3048)
			(end 0.67945 0.3048)
			(stroke
				(width 0.1)
				(type default)
			)
			(layer "F.Fab")
		)
		(fp_line
			(start 0.67945 0.3048)
			(end 0.120396 0.3048)
			(stroke
				(width 0.1)
				(type default)
			)
			(layer "F.Fab")
		)
		(pad "1" smd circle
			(at -0.40005 0)
			(size 0 0)
			(layers "F.Cu" "F.Mask" "F.Paste")
			(net "P12V_SCM_R")
		)
		(pad "2" smd circle
			(at 0.40005 0)
			(size 0 0)
			(layers "F.Cu" "F.Mask" "F.Paste")
			(net "GND")
		)
	)
	(footprint ""
		(layer "F.Cu")
		(at 54.902354 -375.49963 -90)
		(property "Reference" "C823"
			(at 0 0 270)
			(layer "F.SilkS")
			(hide yes)
			(effects
				(font
					(size 1.27 1.27)
				)
			)
		)
		(property "Value" ""
			(at 0 0 270)
			(layer "F.Fab")
			(effects
				(font
					(size 1.27 1.27)
				)
			)
		)
		(duplicate_pad_numbers_are_jumpers no)
		(fp_line
			(start -0.299974 0.150114)
			(end -0.299974 -0.150114)
			(stroke
				(width 0.1)
				(type default)
			)
			(layer "F.Fab")
		)
		(fp_line
			(start 0.299974 0.150114)
			(end -0.299974 0.150114)
			(stroke
				(width 0.1)
				(type default)
			)
			(layer "F.Fab")
		)
		(fp_line
			(start -0.299974 -0.150114)
			(end 0.299974 -0.150114)
			(stroke
				(width 0.1)
				(type default)
			)
			(layer "F.Fab")
		)
		(fp_line
			(start 0.299974 -0.150114)
			(end 0.299974 0.150114)
			(stroke
				(width 0.1)
				(type default)
			)
			(layer "F.Fab")
		)
		(pad "1" smd rect
			(at -0.2667 0 270)
			(size 0.3048 0.381)
			(layers "F.Cu" "F.Mask" "F.Paste")
			(net "P5E_CPU1_P0_TX_C_DP<7>")
		)
		(pad "2" smd rect
			(at 0.2667 0 270)
			(size 0.3048 0.381)
			(layers "F.Cu" "F.Mask" "F.Paste")
			(net "P5E_CPU1_P0_TX_DP<7>")
		)
	)
	(footprint ""
		(layer "F.Cu")
		(at 366.403128 -324.29704 90)
		(property "Reference" "R2659"
			(at 0 0 90)
			(layer "F.SilkS")
			(hide yes)
			(effects
				(font
					(size 1.27 1.27)
				)
			)
		)
		(property "Value" ""
			(at 0 0 90)
			(layer "F.Fab")
			(effects
				(font
					(size 1.27 1.27)
				)
			)
		)
		(duplicate_pad_numbers_are_jumpers no)
		(fp_line
			(start -0.34544 -0.4064)
			(end 0.39116 -0.4064)
			(stroke
				(width 0.1524)
				(type default)
			)
			(layer "F.SilkS")
		)
		(fp_line
			(start 0.7874 0.017272)
			(end 0.7874 0.4064)
			(stroke
				(width 0.1524)
				(type default)
			)
			(layer "F.SilkS")
		)
		(fp_line
			(start 0.7874 0.4064)
			(end -0.7874 0.4064)
			(stroke
				(width 0.1524)
				(type default)
			)
			(layer "F.SilkS")
		)
		(fp_line
			(start -0.7874 0.4064)
			(end -0.7874 0.068072)
			(stroke
				(width 0.1524)
				(type default)
			)
			(layer "F.SilkS")
		)
		(fp_line
			(start -0.12065 -0.305054)
			(end -0.12065 -0.2794)
			(stroke
				(width 0.1)
				(type default)
			)
			(layer "F.Fab")
		)
		(fp_line
			(start -0.67945 -0.305054)
			(end -0.12065 -0.305054)
			(stroke
				(width 0.1)
				(type default)
			)
			(layer "F.Fab")
		)
		(fp_line
			(start 0.67945 -0.3048)
			(end 0.67945 0.3048)
			(stroke
				(width 0.1)
				(type default)
			)
			(layer "F.Fab")
		)
		(fp_line
			(start 0.12065 -0.3048)
			(end 0.67945 -0.3048)
			(stroke
				(width 0.1)
				(type default)
			)
			(layer "F.Fab")
		)
		(fp_line
			(start 0.12065 -0.2794)
			(end 0.12065 -0.3048)
			(stroke
				(width 0.1)
				(type default)
			)
			(layer "F.Fab")
		)
		(fp_line
			(start -0.12065 -0.2794)
			(end 0.12065 -0.2794)
			(stroke
				(width 0.1)
				(type default)
			)
			(layer "F.Fab")
		)
		(fp_line
			(start 0.120396 0.2794)
			(end -0.12065 0.2794)
			(stroke
				(width 0.1)
				(type default)
			)
			(layer "F.Fab")
		)
		(fp_line
			(start -0.12065 0.2794)
			(end -0.12065 0.3048)
			(stroke
				(width 0.1)
				(type default)
			)
			(layer "F.Fab")
		)
		(fp_line
			(start 0.67945 0.3048)
			(end 0.120396 0.3048)
			(stroke
				(width 0.1)
				(type default)
			)
			(layer "F.Fab")
		)
		(fp_line
			(start 0.120396 0.3048)
			(end 0.120396 0.2794)
			(stroke
				(width 0.1)
				(type default)
			)
			(layer "F.Fab")
		)
		(fp_line
			(start -0.12065 0.3048)
			(end -0.67945 0.3048)
			(stroke
				(width 0.1)
				(type default)
			)
			(layer "F.Fab")
		)
		(fp_line
			(start -0.67945 0.3048)
			(end -0.67945 -0.305054)
			(stroke
				(width 0.1)
				(type default)
			)
			(layer "F.Fab")
		)
		(pad "1" smd circle
			(at -0.40005 0 90)
			(size 0 0)
			(layers "F.Cu" "F.Mask" "F.Paste")
			(net "CLK_100M_CPU0_CLK11_R_DP")
		)
		(pad "2" smd circle
			(at 0.40005 0 90)
			(size 0 0)
			(layers "F.Cu" "F.Mask" "F.Paste")
			(net "CLK_100M_CPU0_CLK11_DP")
		)
	)
	(footprint ""
		(layer "F.Cu")
		(at 24.804878 -17.623536 90)
		(property "Reference" "C685"
			(at 0 0 90)
			(layer "F.SilkS")
			(hide yes)
			(effects
				(font
					(size 1.27 1.27)
				)
			)
		)
		(property "Value" ""
			(at 0 0 90)
			(layer "F.Fab")
			(effects
				(font
					(size 1.27 1.27)
				)
			)
		)
		(duplicate_pad_numbers_are_jumpers no)
		(fp_line
			(start 0.299974 -0.150114)
			(end 0.299974 0.150114)
			(stroke
				(width 0.1)
				(type default)
			)
			(layer "F.Fab")
		)
		(fp_line
			(start -0.299974 -0.150114)
			(end 0.299974 -0.150114)
			(stroke
				(width 0.1)
				(type default)
			)
			(layer "F.Fab")
		)
		(fp_line
			(start 0.299974 0.150114)
			(end -0.299974 0.150114)
			(stroke
				(width 0.1)
				(type default)
			)
			(layer "F.Fab")
		)
		(fp_line
			(start -0.299974 0.150114)
			(end -0.299974 -0.150114)
			(stroke
				(width 0.1)
				(type default)
			)
			(layer "F.Fab")
		)
		(pad "1" smd rect
			(at -0.2667 0 90)
			(size 0.3048 0.381)
			(layers "F.Cu" "F.Mask" "F.Paste")
			(net "P5E_CPU1_G1_TX_C_DP<12>")
		)
		(pad "2" smd rect
			(at 0.2667 0 90)
			(size 0.3048 0.381)
			(layers "F.Cu" "F.Mask" "F.Paste")
			(net "P5E_CPU1_G1_TX_DP<12>")
		)
	)
	(footprint ""
		(layer "F.Cu")
		(at 413.977582 -333.271114)
		(property "Reference" "TP8"
			(at -5.141722 -0.386588 0)
			(unlocked yes)
			(layer "F.SilkS")
			(effects
				(font
					(size 0.7874 0.5842)
					(thickness 0.1524)
				)
				(justify left)
			)
		)
		(property "Value" ""
			(at 0 0 0)
			(layer "F.Fab")
			(effects
				(font
					(size 1.27 1.27)
				)
			)
		)
		(duplicate_pad_numbers_are_jumpers no)
		(pad "1" smd circle
			(at 0 0)
			(size 0.762 0.762)
			(layers "F.Cu" "F.Mask" "F.Paste")
			(net "VSENSE_PVDD11_S3_P0_DP")
		)
	)
)
